FILE_TYPE = MACRO_DRAWING;
SET COLOR_WIRE YELLOW;
SET COLOR_PROP ORANGE;
SET COLOR_DOT WHITE;
SET COLOR_ARC YELLOW;
SET COLOR_BODY GREEN;
SET COLOR_NOTE PURPLE;
SET PROP_DISPLAY VALUE;
SET PAGE_NUMBER P215;
FORCEADD OFFPAGE..3
R 2
(-2550 1725);
FORCEPROP 2 LAST $XR0 241 
J 0
(-2830 1725);
DISPLAY 0.638298 (-2830 1725);
PAINT MONO (-2830 1725);
FORCEPROP 2 LAST CDS_LIB standard
J 0
(-2550 1725);
PAINT MONO (-2550 1725);
DISPLAY INVISIBLE (-2550 1725);
FORCEPROP 1 LAST COMMENT_BODY TRUE
J 2
(-2500 1625);
DISPLAY 0.872340 (-2500 1625);
PAINT GREEN (-2500 1625);
DISPLAY INVISIBLE (-2500 1625);
FORCEPROP 1 LAST OFFPAGE TRUE
J 2
(-2875 1600);
DISPLAY 0.872340 (-2875 1600);
DISPLAY INVISIBLE (-2875 1600);
FORCEPROP 2 LAST PATH I10
J 0
(-2850 1775);
DISPLAY 1.021277 (-2850 1775);
DISPLAY INVISIBLE (-2850 1775);
FORCEADD OFFPAGE..1
(-2550 1925);
FORCEPROP 2 LAST $XR0 241 
J 0
(-2802 1925);
DISPLAY 0.638298 (-2802 1925);
PAINT MONO (-2802 1925);
FORCEPROP 1 LAST OFFPAGE TRUE
J 0
(-2225 1800);
DISPLAY 0.872340 (-2225 1800);
PAINT GREEN (-2225 1800);
DISPLAY INVISIBLE (-2225 1800);
FORCEPROP 1 LAST COMMENT_BODY TRUE
J 0
(-2425 1825);
DISPLAY 0.872340 (-2425 1825);
PAINT GREEN (-2425 1825);
DISPLAY INVISIBLE (-2425 1825);
FORCEPROP 2 LAST CDS_LIB standard
J 0
(-2550 1925);
PAINT MONO (-2550 1925);
DISPLAY INVISIBLE (-2550 1925);
FORCEPROP 2 LAST PATH I11
J 0
(-2825 1975);
DISPLAY 1.021277 (-2825 1975);
DISPLAY INVISIBLE (-2825 1975);
FORCEADD Q_RES..1
(-1400 1725);
FORCEPROP 1 LAST PART_NUMBER CS03322FB03
J 0
(-1525 1775);
DISPLAY 0.638298 (-1525 1775);
DISPLAY INVISIBLE (-1525 1775);
FORCEPROP 1 LAST VALUE 33.2
J 2
(-1200 1725);
DISPLAY 0.510638 (-1200 1725);
FORCEPROP 1 LAST TOLERANCE 1%
J 0
(-1175 1725);
DISPLAY 0.510638 (-1175 1725);
FORCEPROP 1 LAST MATERIAL CHIP
J 0
(-1100 1725);
DISPLAY 0.510638 (-1100 1725);
FORCEPROP 1 LAST $LOCATION R3053
J 0
(-1675 1725);
DISPLAY 0.787234 (-1675 1725);
FORCEPROP 1 LASTPIN (-1500 1725) $PN 1
J 0
(-1488 1737);
DISPLAY 0.787234 (-1488 1737);
FORCEPROP 1 LASTPIN (-1300 1725) $PN 2
J 0
(-1338 1737);
DISPLAY 0.787234 (-1338 1737);
FORCEPROP 1 LAST PATH I12
J 0
(-1450 1875);
DISPLAY 0.978723 (-1450 1875);
PAINT WHITE (-1450 1875);
DISPLAY INVISIBLE (-1450 1875);
FORCEPROP 1 LAST PACK_TYPE 0402LF
J 0
(-1050 1725);
DISPLAY 0.638298 (-1050 1725);
DISPLAY INVISIBLE (-1050 1725);
FORCEPROP 2 LAST CDS_LIB pure_quanta
J 0
(-1400 1725);
PAINT MONO (-1400 1725);
DISPLAY INVISIBLE (-1400 1725);
FORCEPROP 1 LAST WATTAGE 1/16W
J 2
(-1200 1825);
DISPLAY 0.638298 (-1200 1825);
DISPLAY INVISIBLE (-1200 1825);
FORCEPROP 2 LAST CDS_LOCATION R3053
J 0
(-1450 1925);
DISPLAY 1.021277 (-1450 1925);
DISPLAY INVISIBLE (-1450 1925);
FORCEPROP 2 LAST $SEC 1
J 0
(-1450 1925);
DISPLAY 0.680851 (-1450 1925);
PAINT MONO (-1450 1925);
DISPLAY INVISIBLE (-1450 1925);
FORCEPROP 2 LAST CDS_SEC 1
J 0
(-1450 1925);
DISPLAY 1.021277 (-1450 1925);
DISPLAY INVISIBLE (-1450 1925);
FORCEADD Q_RES..1
(-1400 1925);
FORCEPROP 1 LAST PART_NUMBER CS03322FB03
J 0
(-1525 2000);
DISPLAY 0.510638 (-1525 2000);
DISPLAY INVISIBLE (-1525 2000);
FORCEPROP 1 LAST WATTAGE 1/16W
J 2
(-1225 2050);
DISPLAY 0.510638 (-1225 2050);
FORCEPROP 1 LAST VALUE 33.2
J 2
(-1200 1925);
DISPLAY 0.510638 (-1200 1925);
FORCEPROP 1 LAST MATERIAL CHIP
J 0
(-1100 1925);
DISPLAY 0.510638 (-1100 1925);
FORCEPROP 1 LAST TOLERANCE 1%
J 0
(-1175 1925);
DISPLAY 0.510638 (-1175 1925);
FORCEPROP 1 LAST PACK_TYPE 0402LF
J 0
(-1525 2050);
DISPLAY 0.510638 (-1525 2050);
FORCEPROP 1 LAST $LOCATION R3052
J 0
(-1675 1925);
DISPLAY 0.787234 (-1675 1925);
FORCEPROP 1 LASTPIN (-1500 1925) $PN 1
J 0
(-1488 1937);
DISPLAY 0.787234 (-1488 1937);
FORCEPROP 1 LASTPIN (-1300 1925) $PN 2
J 0
(-1338 1937);
DISPLAY 0.787234 (-1338 1937);
FORCEPROP 1 LAST PATH I13
J 0
(-1450 2075);
DISPLAY 0.978723 (-1450 2075);
PAINT WHITE (-1450 2075);
DISPLAY INVISIBLE (-1450 2075);
FORCEPROP 2 LAST CDS_LIB pure_quanta
J 0
(-1400 1925);
PAINT MONO (-1400 1925);
DISPLAY INVISIBLE (-1400 1925);
FORCEPROP 2 LAST CDS_LOCATION R3052
J 0
(-1450 2125);
DISPLAY 1.021277 (-1450 2125);
DISPLAY INVISIBLE (-1450 2125);
FORCEPROP 2 LAST $SEC 1
J 0
(-1450 2125);
DISPLAY 0.680851 (-1450 2125);
PAINT MONO (-1450 2125);
DISPLAY INVISIBLE (-1450 2125);
FORCEPROP 2 LAST CDS_SEC 1
J 0
(-1450 2125);
DISPLAY 1.021277 (-1450 2125);
DISPLAY INVISIBLE (-1450 2125);
FORCEADD OFFPAGE..2
(-150 1925);
FORCEPROP 2 LAST $XR0 228 
J 0
(39 1925);
DISPLAY 0.638298 (39 1925);
PAINT MONO (39 1925);
FORCEPROP 2 LAST PATH I14
J 0
(50 1975);
DISPLAY 1.021277 (50 1975);
DISPLAY INVISIBLE (50 1975);
FORCEPROP 2 LAST CDS_LIB standard
J 0
(-150 1925);
PAINT MONO (-150 1925);
DISPLAY INVISIBLE (-150 1925);
FORCEPROP 1 LAST COMMENT_BODY TRUE
J 0
(-195 1830);
DISPLAY 0.872340 (-195 1830);
PAINT GREEN (-195 1830);
DISPLAY INVISIBLE (-195 1830);
FORCEPROP 1 LAST OFFPAGE TRUE
J 0
(175 1800);
DISPLAY 0.872340 (175 1800);
PAINT GREEN (175 1800);
DISPLAY INVISIBLE (175 1800);
FORCEADD OFFPAGE..3
(-150 1725);
FORCEPROP 2 LAST $XR0 228 
J 0
(64 1725);
DISPLAY 0.638298 (64 1725);
PAINT MONO (64 1725);
FORCEPROP 2 LAST PATH I15
J 0
(75 1775);
DISPLAY 1.021277 (75 1775);
DISPLAY INVISIBLE (75 1775);
FORCEPROP 2 LAST CDS_LIB standard
J 0
(-150 1725);
PAINT MONO (-150 1725);
DISPLAY INVISIBLE (-150 1725);
FORCEPROP 1 LAST OFFPAGE TRUE
J 0
(175 1600);
DISPLAY 0.872340 (175 1600);
PAINT GREEN (175 1600);
DISPLAY INVISIBLE (175 1600);
FORCEPROP 1 LAST COMMENT_BODY TRUE
J 0
(-200 1625);
DISPLAY 0.872340 (-200 1625);
PAINT GREEN (-200 1625);
DISPLAY INVISIBLE (-200 1625);
FORCEADD OFFPAGE..1
(-2950 3250);
FORCEPROP 2 LAST $XR0 228 
J 0
(-3202 3250);
DISPLAY 0.638298 (-3202 3250);
PAINT MONO (-3202 3250);
FORCEPROP 2 LAST CDS_LIB standard
J 0
(-2950 3250);
DISPLAY INVISIBLE (-2950 3250);
FORCEPROP 2 LAST PATH I17
J 0
(-2900 3325);
DISPLAY 1.021277 (-2900 3325);
DISPLAY INVISIBLE (-2900 3325);
FORCEPROP 1 LAST COMMENT_BODY TRUE
J 0
(-2825 3150);
DISPLAY 0.872340 (-2825 3150);
PAINT GREEN (-2825 3150);
DISPLAY INVISIBLE (-2825 3150);
FORCEPROP 1 LAST OFFPAGE TRUE
J 0
(-2625 3125);
DISPLAY 0.872340 (-2625 3125);
DISPLAY INVISIBLE (-2625 3125);
FORCEADD OFFPAGE..3
R 2
(-2950 3200);
FORCEPROP 2 LAST $XR0 228 
J 0
(-3230 3200);
DISPLAY 0.638298 (-3230 3200);
PAINT MONO (-3230 3200);
FORCEPROP 2 LAST CDS_LIB standard
J 0
(-2950 3200);
DISPLAY INVISIBLE (-2950 3200);
FORCEPROP 2 LAST PATH I18
J 0
(-2900 3275);
DISPLAY 1.021277 (-2900 3275);
DISPLAY INVISIBLE (-2900 3275);
FORCEPROP 1 LAST COMMENT_BODY TRUE
J 2
(-2900 3100);
DISPLAY 0.872340 (-2900 3100);
PAINT GREEN (-2900 3100);
DISPLAY INVISIBLE (-2900 3100);
FORCEPROP 1 LAST OFFPAGE TRUE
J 2
(-3275 3075);
DISPLAY 0.872340 (-3275 3075);
DISPLAY INVISIBLE (-3275 3075);
FORCEADD OFFPAGE..1
(-2950 3050);
FORCEPROP 2 LAST $XR0 205 
J 0
(-3202 3050);
DISPLAY 0.638298 (-3202 3050);
PAINT MONO (-3202 3050);
FORCEPROP 2 LAST CDS_LIB standard
J 0
(-2950 3050);
DISPLAY INVISIBLE (-2950 3050);
FORCEPROP 2 LAST PATH I19
J 0
(-2900 3125);
DISPLAY 1.021277 (-2900 3125);
DISPLAY INVISIBLE (-2900 3125);
FORCEPROP 1 LAST OFFPAGE TRUE
J 0
(-2625 2925);
DISPLAY 0.872340 (-2625 2925);
DISPLAY INVISIBLE (-2625 2925);
FORCEPROP 1 LAST COMMENT_BODY TRUE
J 0
(-2825 2950);
DISPLAY 0.872340 (-2825 2950);
PAINT GREEN (-2825 2950);
DISPLAY INVISIBLE (-2825 2950);
FORCEADD Q_RES..1
(-1400 2150);
FORCEPROP 1 LAST PART_NUMBER CS00002JB13
J 0
(-1450 2200);
DISPLAY 0.404255 (-1450 2200);
DISPLAY INVISIBLE (-1450 2200);
FORCEPROP 1 LAST VALUE 0
J 2
(-1250 2150);
DISPLAY 0.510638 (-1250 2150);
FORCEPROP 1 LAST TOLERANCE 5%
J 0
(-1225 2150);
DISPLAY 0.510638 (-1225 2150);
FORCEPROP 1 LAST MATERIAL CHIP
J 0
(-1150 2150);
DISPLAY 0.510638 (-1150 2150);
FORCEPROP 1 LAST $LOCATION R3051
J 0
(-1600 2150);
DISPLAY 0.510638 (-1600 2150);
FORCEPROP 1 LASTPIN (-1500 2150) $PN 1
J 0
(-1488 2162);
DISPLAY 0.787234 (-1488 2162);
PAINT MONO (-1488 2162);
FORCEPROP 1 LASTPIN (-1300 2150) $PN 2
J 0
(-1338 2162);
DISPLAY 0.787234 (-1338 2162);
PAINT MONO (-1338 2162);
FORCEPROP 1 LAST WATTAGE 1/16W
J 2
(-1225 2225);
DISPLAY 0.404255 (-1225 2225);
DISPLAY INVISIBLE (-1225 2225);
FORCEPROP 1 LAST PACK_TYPE 0402LF
J 0
(-1150 2150);
DISPLAY 0.510638 (-1150 2150);
DISPLAY INVISIBLE (-1150 2150);
FORCEPROP 2 LAST CDS_LIB pure_quanta
J 0
(-1400 2150);
DISPLAY INVISIBLE (-1400 2150);
FORCEPROP 1 LAST PATH I2
J 0
(-1450 2300);
DISPLAY 0.978723 (-1450 2300);
PAINT WHITE (-1450 2300);
DISPLAY INVISIBLE (-1450 2300);
FORCEPROP 0 LAST CDS_LOCATION R3051
J 0
(-1150 2175);
DISPLAY 1.021277 (-1150 2175);
DISPLAY INVISIBLE (-1150 2175);
FORCEPROP 0 LAST $SEC 1
J 0
(-1150 2175);
DISPLAY 0.680851 (-1150 2175);
PAINT MONO (-1150 2175);
DISPLAY INVISIBLE (-1150 2175);
FORCEPROP 0 LAST CDS_SEC 1
J 0
(-1150 2175);
DISPLAY 1.021277 (-1150 2175);
DISPLAY INVISIBLE (-1150 2175);
FORCEADD OFFPAGE..1
(-2950 3300);
FORCEPROP 2 LAST $XR0 223 
J 0
(-3232 3300);
DISPLAY 0.638298 (-3232 3300);
PAINT MONO (-3232 3300);
FORCEPROP 1 LAST OFFPAGE TRUE
J 0
(-2625 3175);
DISPLAY 0.872340 (-2625 3175);
DISPLAY INVISIBLE (-2625 3175);
FORCEPROP 1 LAST COMMENT_BODY TRUE
J 0
(-2825 3200);
DISPLAY 0.872340 (-2825 3200);
PAINT GREEN (-2825 3200);
DISPLAY INVISIBLE (-2825 3200);
FORCEPROP 2 LAST PATH I20
J 0
(-2900 3375);
DISPLAY 1.021277 (-2900 3375);
DISPLAY INVISIBLE (-2900 3375);
FORCEPROP 2 LAST CDS_LIB standard
J 0
(-2950 3300);
DISPLAY INVISIBLE (-2950 3300);
FORCEADD UNIVERSAL_GND..1
(-1900 2800);
FORCEPROP 3 LASTPIN (-1900 2850) SIG_NAME GND\g
J 0
(-1890 2860);
DISPLAY 0.659574 (-1890 2860);
PAINT MONO (-1890 2860);
DISPLAY INVISIBLE (-1890 2860);
FORCEPROP 2 LAST CDS_LIB logical_power
J 0
(-1900 2800);
DISPLAY INVISIBLE (-1900 2800);
FORCEPROP 1 LAST PATH I21
J 0
(-1825 2800);
DISPLAY 0.872340 (-1825 2800);
PAINT AQUA (-1825 2800);
DISPLAY INVISIBLE (-1825 2800);
FORCEPROP 1 LAST HDL_POWER GND
J 1
(-1875 2725);
DISPLAY 0.872340 (-1875 2725);
PAINT GREEN (-1875 2725);
DISPLAY INVISIBLE (-1875 2725);
FORCEADD Q_RES..1
(-125 3100);
FORCEPROP 1 LAST PART_NUMBER CS03322FB03
J 0
(-250 3150);
DISPLAY 0.404255 (-250 3150);
DISPLAY INVISIBLE (-250 3150);
FORCEPROP 1 LAST TOLERANCE 1%
J 0
(100 3100);
DISPLAY 0.510638 (100 3100);
FORCEPROP 1 LAST VALUE 33.2
J 2
(75 3100);
DISPLAY 0.510638 (75 3100);
FORCEPROP 1 LAST MATERIAL CHIP
J 0
(175 3100);
DISPLAY 0.510638 (175 3100);
FORCEPROP 1 LAST $LOCATION R3054
J 0
(-350 3100);
DISPLAY 0.638298 (-350 3100);
FORCEPROP 1 LASTPIN (-225 3100) $PN 1
J 0
(-213 3112);
DISPLAY 0.787234 (-213 3112);
PAINT MONO (-213 3112);
FORCEPROP 1 LASTPIN (-25 3100) $PN 2
J 0
(-63 3112);
DISPLAY 0.787234 (-63 3112);
PAINT MONO (-63 3112);
FORCEPROP 1 LAST WATTAGE 1/16W
J 2
(-25 3200);
DISPLAY 0.404255 (-25 3200);
DISPLAY INVISIBLE (-25 3200);
FORCEPROP 1 LAST PACK_TYPE 0402LF
J 0
(-250 3200);
DISPLAY 0.404255 (-250 3200);
DISPLAY INVISIBLE (-250 3200);
FORCEPROP 2 LAST CDS_LIB pure_quanta
J 0
(-125 3100);
DISPLAY INVISIBLE (-125 3100);
FORCEPROP 1 LAST PATH I23
J 0
(-175 3250);
DISPLAY 0.978723 (-175 3250);
PAINT WHITE (-175 3250);
DISPLAY INVISIBLE (-175 3250);
FORCEPROP 0 LAST CDS_LOCATION R3054
J 0
(-350 3150);
DISPLAY 1.021277 (-350 3150);
DISPLAY INVISIBLE (-350 3150);
FORCEPROP 0 LAST $SEC 1
J 0
(-350 3150);
DISPLAY 0.680851 (-350 3150);
PAINT MONO (-350 3150);
DISPLAY INVISIBLE (-350 3150);
FORCEPROP 0 LAST CDS_SEC 1
J 0
(-350 3150);
DISPLAY 1.021277 (-350 3150);
DISPLAY INVISIBLE (-350 3150);
FORCEADD OFFPAGE..1
R 2
(775 3100);
FORCEPROP 2 LAST $XR1 240 
J 0
(1081 3100);
DISPLAY 0.638298 (1081 3100);
PAINT MONO (1081 3100);
FORCEPROP 2 LAST $XR0 214 
J 0
(961 3100);
DISPLAY 0.638298 (961 3100);
PAINT MONO (961 3100);
FORCEPROP 2 LAST PATH I24
J 2
(725 3175);
DISPLAY 1.021277 (725 3175);
DISPLAY INVISIBLE (725 3175);
FORCEPROP 2 LAST CDS_LIB standard
J 2
(775 3100);
DISPLAY INVISIBLE (775 3100);
FORCEPROP 1 LAST COMMENT_BODY TRUE
J 2
(650 3000);
DISPLAY 0.872340 (650 3000);
PAINT GREEN (650 3000);
DISPLAY INVISIBLE (650 3000);
FORCEPROP 1 LAST OFFPAGE TRUE
J 2
(450 2975);
DISPLAY 0.872340 (450 2975);
DISPLAY INVISIBLE (450 2975);
FORCEADD OFFPAGE..3
(775 3150);
FORCEPROP 2 LAST $XR0 197 
J 0
(989 3150);
DISPLAY 0.638298 (989 3150);
PAINT MONO (989 3150);
FORCEPROP 2 LAST CDS_LIB standard
J 2
(775 3150);
DISPLAY INVISIBLE (775 3150);
FORCEPROP 2 LAST PATH I26
J 2
(725 3225);
DISPLAY 1.021277 (725 3225);
DISPLAY INVISIBLE (725 3225);
FORCEPROP 1 LAST OFFPAGE TRUE
J 0
(1100 3025);
DISPLAY 0.872340 (1100 3025);
DISPLAY INVISIBLE (1100 3025);
FORCEPROP 1 LAST COMMENT_BODY TRUE
J 0
(725 3050);
DISPLAY 0.872340 (725 3050);
PAINT GREEN (725 3050);
DISPLAY INVISIBLE (725 3050);
FORCEADD UNIVERSAL_GND..1
(-1150 2800);
FORCEPROP 3 LASTPIN (-1150 2850) SIG_NAME GND\g
J 0
(-1140 2860);
DISPLAY 0.659574 (-1140 2860);
PAINT MONO (-1140 2860);
DISPLAY INVISIBLE (-1140 2860);
FORCEPROP 1 LAST HDL_POWER GND
J 1
(-1125 2725);
DISPLAY 0.872340 (-1125 2725);
PAINT GREEN (-1125 2725);
DISPLAY INVISIBLE (-1125 2725);
FORCEPROP 1 LAST PATH I27
J 0
(-1075 2800);
DISPLAY 0.872340 (-1075 2800);
PAINT AQUA (-1075 2800);
DISPLAY INVISIBLE (-1075 2800);
FORCEPROP 2 LAST CDS_LIB logical_power
J 0
(-1150 2800);
DISPLAY INVISIBLE (-1150 2800);
FORCEADD Q_RES..1
(-1400 2325);
FORCEPROP 1 LAST PART_NUMBER CS00002JB13
J 0
(-1450 2375);
DISPLAY 0.404255 (-1450 2375);
DISPLAY INVISIBLE (-1450 2375);
FORCEPROP 1 LAST VALUE 0
J 2
(-1250 2325);
DISPLAY 0.510638 (-1250 2325);
FORCEPROP 1 LAST MATERIAL CHIP
J 0
(-1150 2325);
DISPLAY 0.510638 (-1150 2325);
FORCEPROP 1 LAST TOLERANCE 5%
J 0
(-1225 2325);
DISPLAY 0.510638 (-1225 2325);
FORCEPROP 1 LAST $LOCATION R3103
J 0
(-1600 2325);
DISPLAY 0.510638 (-1600 2325);
FORCEPROP 1 LASTPIN (-1500 2325) $PN 1
J 0
(-1488 2337);
DISPLAY 0.787234 (-1488 2337);
PAINT MONO (-1488 2337);
FORCEPROP 1 LASTPIN (-1300 2325) $PN 2
J 0
(-1338 2337);
DISPLAY 0.787234 (-1338 2337);
PAINT MONO (-1338 2337);
FORCEPROP 1 LAST PATH I28
J 0
(-1450 2475);
DISPLAY 0.978723 (-1450 2475);
PAINT WHITE (-1450 2475);
DISPLAY INVISIBLE (-1450 2475);
FORCEPROP 2 LAST CDS_LIB pure_quanta
J 0
(-1400 2325);
DISPLAY INVISIBLE (-1400 2325);
FORCEPROP 1 LAST PACK_TYPE 0402LF
J 0
(-1150 2325);
DISPLAY 0.510638 (-1150 2325);
DISPLAY INVISIBLE (-1150 2325);
FORCEPROP 1 LAST WATTAGE 1/16W
J 2
(-1225 2400);
DISPLAY 0.404255 (-1225 2400);
DISPLAY INVISIBLE (-1225 2400);
FORCEPROP 0 LAST CDS_LOCATION R3103
J 0
(-1150 2350);
DISPLAY 1.021277 (-1150 2350);
DISPLAY INVISIBLE (-1150 2350);
FORCEPROP 0 LAST $SEC 1
J 0
(-1150 2350);
DISPLAY 0.680851 (-1150 2350);
PAINT MONO (-1150 2350);
DISPLAY INVISIBLE (-1150 2350);
FORCEPROP 0 LAST CDS_SEC 1
J 0
(-1150 2350);
DISPLAY 1.021277 (-1150 2350);
DISPLAY INVISIBLE (-1150 2350);
FORCEADD OFFPAGE..2
(-150 2325);
FORCEPROP 2 LAST $XR0 228 
J 0
(39 2325);
DISPLAY 0.638298 (39 2325);
PAINT MONO (39 2325);
FORCEPROP 2 LAST PATH I29
J 0
(300 2375);
DISPLAY 1.021277 (300 2375);
DISPLAY INVISIBLE (300 2375);
FORCEPROP 1 LAST COMMENT_BODY TRUE
J 0
(-195 2230);
DISPLAY 0.872340 (-195 2230);
PAINT PEACH (-195 2230);
DISPLAY INVISIBLE (-195 2230);
FORCEPROP 1 LAST OFFPAGE TRUE
J 0
(175 2200);
DISPLAY 0.872340 (175 2200);
PAINT GREEN (175 2200);
DISPLAY INVISIBLE (175 2200);
FORCEPROP 2 LAST CDS_LIB standard
J 0
(-150 2325);
PAINT MONO (-150 2325);
DISPLAY INVISIBLE (-150 2325);
FORCEADD OFFPAGE..2
(-150 2150);
FORCEPROP 2 LAST $XR3 215 
J 0
(399 2150);
DISPLAY 0.638298 (399 2150);
PAINT MONO (399 2150);
FORCEPROP 2 LAST $XR2 183 
J 0
(279 2150);
DISPLAY 0.638298 (279 2150);
PAINT MONO (279 2150);
FORCEPROP 2 LAST $XR1 305 
J 0
(159 2150);
DISPLAY 0.638298 (159 2150);
PAINT MONO (159 2150);
FORCEPROP 2 LAST $XR0 301 
J 0
(39 2150);
DISPLAY 0.638298 (39 2150);
PAINT MONO (39 2150);
FORCEPROP 2 LAST CDS_LIB standard
J 0
(-150 2150);
PAINT MONO (-150 2150);
DISPLAY INVISIBLE (-150 2150);
FORCEPROP 1 LAST OFFPAGE TRUE
J 0
(175 2025);
DISPLAY 0.872340 (175 2025);
PAINT GREEN (175 2025);
DISPLAY INVISIBLE (175 2025);
FORCEPROP 1 LAST COMMENT_BODY TRUE
J 0
(-195 2055);
DISPLAY 0.872340 (-195 2055);
PAINT PEACH (-195 2055);
DISPLAY INVISIBLE (-195 2055);
FORCEPROP 2 LAST PATH I3
J 0
(50 2200);
DISPLAY 1.021277 (50 2200);
DISPLAY INVISIBLE (50 2200);
FORCEADD OFFPAGE..1
(-2550 2325);
FORCEPROP 2 LAST $XR1 213 
J 0
(-2922 2325);
DISPLAY 0.638298 (-2922 2325);
PAINT MONO (-2922 2325);
FORCEPROP 2 LAST $XR0 183 
J 0
(-2802 2325);
DISPLAY 0.638298 (-2802 2325);
PAINT MONO (-2802 2325);
FORCEPROP 2 LAST PATH I30
J 0
(-2800 2375);
DISPLAY 1.021277 (-2800 2375);
DISPLAY INVISIBLE (-2800 2375);
FORCEPROP 2 LAST CDS_LIB standard
J 0
(-2550 2325);
DISPLAY INVISIBLE (-2550 2325);
FORCEPROP 1 LAST COMMENT_BODY TRUE
J 0
(-2425 2225);
DISPLAY 1.170213 (-2425 2225);
PAINT GREEN (-2425 2225);
DISPLAY INVISIBLE (-2425 2225);
FORCEPROP 1 LAST OFFPAGE TRUE
J 0
(-2225 2200);
DISPLAY 0.872340 (-2225 2200);
DISPLAY INVISIBLE (-2225 2200);
FORCEADD OFFPAGE..2
(-100 3450);
FORCEPROP 2 LAST $XR0 228 
J 0
(89 3450);
DISPLAY 0.638298 (89 3450);
PAINT MONO (89 3450);
FORCEPROP 2 LAST PATH I31
J 0
(100 3500);
DISPLAY 1.021277 (100 3500);
DISPLAY INVISIBLE (100 3500);
FORCEPROP 1 LAST COMMENT_BODY TRUE
J 0
(-145 3355);
DISPLAY 0.872340 (-145 3355);
PAINT PEACH (-145 3355);
DISPLAY INVISIBLE (-145 3355);
FORCEPROP 1 LAST OFFPAGE TRUE
J 0
(225 3325);
DISPLAY 0.872340 (225 3325);
PAINT GREEN (225 3325);
DISPLAY INVISIBLE (225 3325);
FORCEPROP 2 LAST CDS_LIB standard
J 0
(-100 3450);
DISPLAY INVISIBLE (-100 3450);
FORCEADD SCONN20_513860200CV01..1
(-1525 3275);
FORCEPROP 1 LAST PART_NUMBER DFHD20MS193
J 0
(-1675 3625);
DISPLAY 0.723404 (-1675 3625);
PAINT GREEN (-1675 3625);
DISPLAY INVISIBLE (-1675 3625);
FORCEPROP 2 LAST PART_TYPE SMLF
J 0
(-1658 3804);
DISPLAY 1.021277 (-1658 3804);
FORCEPROP 1 LAST MATERIAL IO
J 0
(-1667 3572);
DISPLAY 0.723404 (-1667 3572);
PAINT GREEN (-1667 3572);
FORCEPROP 2 LAST VALUE SCONN20_51386-0200C-V01
J 0
(-1658 3754);
DISPLAY 1.021277 (-1658 3754);
FORCEPROP 1 LAST LOCATION J100
J 0
(-1675 3700);
DISPLAY 0.723404 (-1675 3700);
PAINT GREEN (-1675 3700);
FORCEPROP 0 LASTPIN (-1825 3500) $PN 1
J 2
(-1835 3510);
DISPLAY 0.680851 (-1835 3510);
PAINT MONO (-1835 3510);
FORCEPROP 0 LASTPIN (-1225 3500) $PN 2
J 0
(-1215 3510);
DISPLAY 0.680851 (-1215 3510);
PAINT MONO (-1215 3510);
FORCEPROP 0 LASTPIN (-1825 3450) $PN 3
J 2
(-1835 3460);
DISPLAY 0.680851 (-1835 3460);
PAINT MONO (-1835 3460);
FORCEPROP 0 LASTPIN (-1225 3450) $PN 4
J 0
(-1215 3460);
DISPLAY 0.680851 (-1215 3460);
PAINT MONO (-1215 3460);
FORCEPROP 0 LASTPIN (-1825 3400) $PN 5
J 2
(-1835 3410);
DISPLAY 0.680851 (-1835 3410);
PAINT MONO (-1835 3410);
FORCEPROP 0 LASTPIN (-1225 3400) $PN 6
J 0
(-1215 3410);
DISPLAY 0.680851 (-1215 3410);
PAINT MONO (-1215 3410);
FORCEPROP 0 LASTPIN (-1825 3350) $PN 7
J 2
(-1835 3360);
DISPLAY 0.680851 (-1835 3360);
PAINT MONO (-1835 3360);
FORCEPROP 0 LASTPIN (-1225 3350) $PN 8
J 0
(-1215 3360);
DISPLAY 0.680851 (-1215 3360);
PAINT MONO (-1215 3360);
FORCEPROP 0 LASTPIN (-1825 3300) $PN 9
J 2
(-1835 3310);
DISPLAY 0.680851 (-1835 3310);
PAINT MONO (-1835 3310);
FORCEPROP 0 LASTPIN (-1225 3300) $PN 10
J 0
(-1215 3310);
DISPLAY 0.680851 (-1215 3310);
PAINT MONO (-1215 3310);
FORCEPROP 0 LASTPIN (-1825 3250) $PN 11
J 2
(-1835 3260);
DISPLAY 0.680851 (-1835 3260);
PAINT MONO (-1835 3260);
FORCEPROP 0 LASTPIN (-1225 3250) $PN 12
J 0
(-1215 3260);
DISPLAY 0.680851 (-1215 3260);
PAINT MONO (-1215 3260);
FORCEPROP 0 LASTPIN (-1825 3200) $PN 13
J 2
(-1835 3210);
DISPLAY 0.680851 (-1835 3210);
PAINT MONO (-1835 3210);
FORCEPROP 0 LASTPIN (-1225 3200) $PN 14
J 0
(-1215 3210);
DISPLAY 0.680851 (-1215 3210);
PAINT MONO (-1215 3210);
FORCEPROP 0 LASTPIN (-1825 3150) $PN 15
J 2
(-1835 3160);
DISPLAY 0.680851 (-1835 3160);
PAINT MONO (-1835 3160);
FORCEPROP 0 LASTPIN (-1225 3150) $PN 16
J 0
(-1215 3160);
DISPLAY 0.680851 (-1215 3160);
PAINT MONO (-1215 3160);
FORCEPROP 0 LASTPIN (-1825 3100) $PN 17
J 2
(-1835 3110);
DISPLAY 0.680851 (-1835 3110);
PAINT MONO (-1835 3110);
FORCEPROP 0 LASTPIN (-1225 3100) $PN 18
J 0
(-1215 3110);
DISPLAY 0.680851 (-1215 3110);
PAINT MONO (-1215 3110);
FORCEPROP 0 LASTPIN (-1825 3050) $PN 19
J 2
(-1835 3060);
DISPLAY 0.680851 (-1835 3060);
PAINT MONO (-1835 3060);
FORCEPROP 0 LASTPIN (-1225 3050) $PN 20
J 0
(-1215 3060);
DISPLAY 0.680851 (-1215 3060);
PAINT MONO (-1215 3060);
FORCEPROP 1 LAST CDS_LMAN_SYM_OUTLINE -150,275,150,-275
J 0
(-1525 3275);
DISPLAY 0.468085 (-1525 3275);
PAINT GREEN (-1525 3275);
DISPLAY INVISIBLE (-1525 3275);
FORCEPROP 1 LAST NEEDS_NO_SIZE TRUE
J 0
(-1525 3275);
DISPLAY 0.723404 (-1525 3275);
PAINT GREEN (-1525 3275);
DISPLAY INVISIBLE (-1525 3275);
FORCEPROP 1 LAST PATH I32
J 0
(-1525 3275);
DISPLAY 0.723404 (-1525 3275);
PAINT GREEN (-1525 3275);
DISPLAY INVISIBLE (-1525 3275);
FORCEPROP 2 LAST CDS_LIB pure_quanta
J 0
(-1525 3275);
DISPLAY INVISIBLE (-1525 3275);
FORCEPROP 0 LAST $SEC 1
J 0
(-1650 3875);
DISPLAY 0.680851 (-1650 3875);
PAINT MONO (-1650 3875);
DISPLAY INVISIBLE (-1650 3875);
FORCEPROP 0 LAST CDS_SEC 1
J 0
(-1650 3875);
DISPLAY 1.021277 (-1650 3875);
DISPLAY INVISIBLE (-1650 3875);
FORCEADD OFFPAGE..1
(-2550 2150);
FORCEPROP 2 LAST $XR0 228 
J 0
(-2802 2150);
DISPLAY 0.638298 (-2802 2150);
PAINT MONO (-2802 2150);
FORCEPROP 1 LAST OFFPAGE TRUE
J 0
(-2225 2025);
DISPLAY 0.872340 (-2225 2025);
DISPLAY INVISIBLE (-2225 2025);
FORCEPROP 1 LAST COMMENT_BODY TRUE
J 0
(-2425 2050);
DISPLAY 1.170213 (-2425 2050);
PAINT GREEN (-2425 2050);
DISPLAY INVISIBLE (-2425 2050);
FORCEPROP 2 LAST CDS_LIB standard
J 0
(-2550 2150);
DISPLAY INVISIBLE (-2550 2150);
FORCEPROP 2 LAST PATH I4
J 0
(-2825 2200);
DISPLAY 1.021277 (-2825 2200);
DISPLAY INVISIBLE (-2825 2200);
FORCEADD OFFPAGE..2
(-100 3350);
FORCEPROP 2 LAST $XR0 228 
J 0
(89 3350);
DISPLAY 0.638298 (89 3350);
PAINT MONO (89 3350);
FORCEPROP 2 LAST CDS_LIB standard
J 0
(-100 3350);
DISPLAY INVISIBLE (-100 3350);
FORCEPROP 1 LAST OFFPAGE TRUE
J 0
(225 3225);
DISPLAY 0.872340 (225 3225);
PAINT GREEN (225 3225);
DISPLAY INVISIBLE (225 3225);
FORCEPROP 1 LAST COMMENT_BODY TRUE
J 0
(-145 3255);
DISPLAY 0.872340 (-145 3255);
PAINT PEACH (-145 3255);
DISPLAY INVISIBLE (-145 3255);
FORCEPROP 2 LAST PATH I5
J 0
(75 3425);
DISPLAY 1.021277 (75 3425);
DISPLAY INVISIBLE (75 3425);
FORCEADD OFFPAGE..1
(-2950 3400);
FORCEPROP 2 LAST $XR0 241 
J 0
(-3232 3400);
DISPLAY 0.638298 (-3232 3400);
PAINT MONO (-3232 3400);
FORCEPROP 2 LAST PATH I6
J 0
(-2900 3475);
DISPLAY 1.021277 (-2900 3475);
DISPLAY INVISIBLE (-2900 3475);
FORCEPROP 2 LAST CDS_LIB standard
J 0
(-2950 3400);
DISPLAY INVISIBLE (-2950 3400);
FORCEPROP 1 LAST OFFPAGE TRUE
J 0
(-2625 3275);
DISPLAY 0.872340 (-2625 3275);
DISPLAY INVISIBLE (-2625 3275);
FORCEPROP 1 LAST COMMENT_BODY TRUE
J 0
(-2825 3300);
DISPLAY 0.872340 (-2825 3300);
PAINT GREEN (-2825 3300);
DISPLAY INVISIBLE (-2825 3300);
FORCEADD OFFPAGE..3
R 2
(-2950 3350);
FORCEPROP 2 LAST $XR0 241 
J 0
(-3230 3350);
DISPLAY 0.638298 (-3230 3350);
PAINT MONO (-3230 3350);
FORCEPROP 2 LAST PATH I7
J 0
(-2900 3425);
DISPLAY 1.021277 (-2900 3425);
DISPLAY INVISIBLE (-2900 3425);
FORCEPROP 2 LAST CDS_LIB standard
J 0
(-2950 3350);
DISPLAY INVISIBLE (-2950 3350);
FORCEPROP 1 LAST COMMENT_BODY TRUE
J 2
(-2900 3250);
DISPLAY 0.872340 (-2900 3250);
PAINT GREEN (-2900 3250);
DISPLAY INVISIBLE (-2900 3250);
FORCEPROP 1 LAST OFFPAGE TRUE
J 2
(-3275 3225);
DISPLAY 0.872340 (-3275 3225);
DISPLAY INVISIBLE (-3275 3225);
FORCEADD OFFPAGE..1
(-2950 3500);
FORCEPROP 2 LAST $XR0 241 
J 0
(-3202 3500);
DISPLAY 0.638298 (-3202 3500);
PAINT MONO (-3202 3500);
FORCEPROP 2 LAST CDS_LIB standard
J 0
(-2950 3500);
DISPLAY INVISIBLE (-2950 3500);
FORCEPROP 1 LAST OFFPAGE TRUE
J 0
(-2625 3375);
DISPLAY 0.872340 (-2625 3375);
DISPLAY INVISIBLE (-2625 3375);
FORCEPROP 1 LAST COMMENT_BODY TRUE
J 0
(-2825 3400);
DISPLAY 0.872340 (-2825 3400);
PAINT GREEN (-2825 3400);
DISPLAY INVISIBLE (-2825 3400);
FORCEPROP 2 LAST PATH I8
J 0
(-2900 3575);
DISPLAY 1.021277 (-2900 3575);
DISPLAY INVISIBLE (-2900 3575);
FORCEADD OFFPAGE..3
R 2
(-2950 3450);
FORCEPROP 2 LAST $XR0 241 
J 0
(-3230 3450);
DISPLAY 0.638298 (-3230 3450);
PAINT MONO (-3230 3450);
FORCEPROP 2 LAST PATH I9
J 0
(-2900 3525);
DISPLAY 1.021277 (-2900 3525);
DISPLAY INVISIBLE (-2900 3525);
FORCEPROP 1 LAST OFFPAGE TRUE
J 2
(-3275 3325);
DISPLAY 0.872340 (-3275 3325);
DISPLAY INVISIBLE (-3275 3325);
FORCEPROP 1 LAST COMMENT_BODY TRUE
J 2
(-2900 3350);
DISPLAY 0.872340 (-2900 3350);
PAINT GREEN (-2900 3350);
DISPLAY INVISIBLE (-2900 3350);
FORCEPROP 2 LAST CDS_LIB standard
J 0
(-2950 3450);
DISPLAY INVISIBLE (-2950 3450);
FORCEADD QUANTA_TITLE_BLOCK_C..1
(3550 -575);
FORCEPROP 0 LAST CDS_CON_LAST_MODIFIED Fri Aug 25 14:03:51 2023
J 0
(1665 -560);
DISPLAY INVISIBLE (1665 -560);
FORCEPROP 1 LAST CUSTOM_TXT_CDS <CON_LAST_MODIFIED>
J 0
(1665 -560);
DISPLAY 0.978723 (1665 -560);
FORCEPROP 2 LAST CUSTOM_TXT_CDS <XR_PAGE_TITLE>
J 0
(-4340 4675);
DISPLAY 0.638298 (-4340 4675);
PAINT PINK (-4340 4675);
DISPLAY INVISIBLE (-4340 4675);
FORCEPROP 1 LAST CUSTOM_TXT_CDS <NAME_2>
J 0
(375 -525);
FORCEPROP 1 LAST CUSTOM_TXT_CDS <NAME_1>
J 0
(375 -400);
FORCEPROP 1 LAST CUSTOM_TXT_CDS <Q_NUMBER>
J 0
(2147 -472);
DISPLAY 1.212766 (2147 -472);
FORCEPROP 1 LAST CUSTOM_TXT_CDS <Q_PROJ>
J 0
(1168 -473);
DISPLAY 1.212766 (1168 -473);
FORCEPROP 1 LAST CUSTOM_TXT_CDS <Q_REV>
J 0
(3366 -472);
DISPLAY 1.212766 (3366 -472);
FORCEPROP 1 LAST CUSTOM_TXT_CDS <CON_PAGE_NUM> OF <CON_TOTAL_PAGES>
J 0
(3104 -557);
DISPLAY 0.978723 (3104 -557);
FORCEPROP 1 LAST Q_TITLE NM DEBUG HEADER -(ME CONNECTOR)
J 0
(-5816 -549);
DISPLAY 2.446809 (-5816 -549);
PAINT GREEN (-5816 -549);
FORCEPROP 1 LAST Q_DEPT 
J 1
(-213 -526);
DISPLAY 1.957447 (-213 -526);
PAINT GREEN (-213 -526);
FORCEPROP 2 LAST CDS_XR_PAGE_TITLE CR-228 : @S9S_MB_2U_LIB.S9S_MB_2U(SCH_1):PAGE228
J 0
(-4340 4675);
DISPLAY 0.638298 (-4340 4675);
PAINT PINK (-4340 4675);
DISPLAY INVISIBLE (-4340 4675);
FORCEPROP 2 LAST PAGE_BORDER TRUE
J 0
(-4340 4675);
DISPLAY 0.638298 (-4340 4675);
PAINT PINK (-4340 4675);
DISPLAY INVISIBLE (-4340 4675);
FORCEPROP 1 LAST COMMENT_BODY TRUE
J 0
(3562 -588);
DISPLAY 0.978723 (3562 -588);
PAINT GREEN (3562 -588);
DISPLAY INVISIBLE (3562 -588);
FORCEPROP 1 LAST CDS_LMAN_SYM_OUTLINE -9475,6775,100,-125
J 0
(3550 -575);
DISPLAY 0.468085 (3550 -575);
PAINT GREEN (3550 -575);
DISPLAY INVISIBLE (3550 -575);
FORCEPROP 2 LAST CDS_LIB pure_quanta
J 0
(3550 -575);
DISPLAY INVISIBLE (3550 -575);
WIRE 16 -1 (-1150 3250)(-1150 2850);
WIRE 16 -1 (-1150 3300)(-1150 3250);
WIRE 16 -1 (-1225 3250)(-1150 3250);
WIRE 16 -1 (-1900 3100)(-1900 2850);
WIRE 16 -1 (-1900 3150)(-1900 3100);
WIRE 16 -1 (-1825 3100)(-1900 3100);
WIRE 16 -1 (-2900 3200)(-1825 3200);
FORCEPROP 0 LAST CDS_PHYS_NET_NAME SMB_FRU_U181_3V3AUX_SDA_R
J 0
(-2585 3240);
PAINT MONO (-2585 3240);
DISPLAY INVISIBLE (-2585 3240);
FORCEPROP 2 LAST SIG_NAME SMB_HOST_ME_SDA
J 0
(-2735 3210);
DISPLAY 0.638298 (-2735 3210);
PAINT WHITE (-2735 3210);
WIRE 16 -1 (-1825 3150)(-1900 3150);
WIRE 16 -1 (-1225 3100)(-225 3100);
FORCEPROP 0 LAST CDS_PHYS_NET_NAME SMB_FRU_U181_3V3AUX_SDA_R
J 0
(-910 3140);
PAINT MONO (-910 3140);
DISPLAY INVISIBLE (-910 3140);
FORCEPROP 2 LAST SIG_NAME PWRGD_PS_PWROK_ME_CONN
J 0
(-1085 3110);
DISPLAY 0.638298 (-1085 3110);
PAINT WHITE (-1085 3110);
WIRE 16 -1 (-1225 3150)(725 3150);
FORCEPROP 0 LAST CDS_PHYS_NET_NAME SMB_FRU_U181_3V3AUX_SDA_R
J 0
(-910 3190);
PAINT MONO (-910 3190);
DISPLAY INVISIBLE (-910 3190);
FORCEPROP 2 LAST SIG_NAME PECI_BMC_ME
J 0
(-1085 3160);
DISPLAY 0.638298 (-1085 3160);
PAINT WHITE (-1085 3160);
WIRE 16 -1 (-1300 2325)(-200 2325);
FORCEPROP 0 LAST CDS_PHYS_NET_NAME SMB_FRU_U181_3V3AUX_SDA_R
J 0
(-985 2365);
PAINT MONO (-985 2365);
DISPLAY INVISIBLE (-985 2365);
FORCEPROP 2 LAST SIG_NAME IRQ_SML0_ALERT_R1_N
J 0
(-910 2335);
DISPLAY 0.638298 (-910 2335);
PAINT WHITE (-910 2335);
WIRE 16 -1 (-2500 2150)(-1500 2150);
FORCEPROP 0 LAST CDS_PHYS_NET_NAME SMB_FRU_U181_3V3AUX_SDA
J 0
(-2475 2192);
PAINT MONO (-2475 2192);
DISPLAY INVISIBLE (-2475 2192);
FORCEPROP 0 LAST SIG_NAME IRQ_SML1_PMBUS_ALERT_R_N
J 0
(-2400 2160);
DISPLAY 0.680851 (-2400 2160);
PAINT WHITE (-2400 2160);
WIRE 16 -1 (-1500 1925)(-2500 1925);
FORCEPROP 2 LAST SIG_NAME SMB_HOST_3V3AUX_SCL_R5
J 0
(-2385 1935);
DISPLAY 0.680851 (-2385 1935);
PAINT WHITE (-2385 1935);
WIRE 16 -1 (-1300 2150)(-200 2150);
FORCEPROP 0 LAST CDS_PHYS_NET_NAME SMB_FRU_U181_3V3AUX_SDA_R
J 0
(-985 2190);
PAINT MONO (-985 2190);
DISPLAY INVISIBLE (-985 2190);
FORCEPROP 2 LAST SIG_NAME IRQ_SML1_PMBUS_ALERT_N
J 0
(-910 2160);
DISPLAY 0.638298 (-910 2160);
PAINT WHITE (-910 2160);
WIRE 16 -1 (-2900 3500)(-1825 3500);
FORCEPROP 0 LAST CDS_PHYS_NET_NAME SMB_FRU_U181_3V3AUX_SDA_R
J 0
(-2585 3540);
PAINT MONO (-2585 3540);
DISPLAY INVISIBLE (-2585 3540);
FORCEPROP 2 LAST SIG_NAME SMB_SML0_ME_SCL
J 0
(-2735 3510);
DISPLAY 0.638298 (-2735 3510);
PAINT WHITE (-2735 3510);
WIRE 16 -1 (-2900 3450)(-1825 3450);
FORCEPROP 0 LAST CDS_PHYS_NET_NAME SMB_FRU_U181_3V3AUX_SDA_R
J 0
(-2585 3490);
PAINT MONO (-2585 3490);
DISPLAY INVISIBLE (-2585 3490);
FORCEPROP 2 LAST SIG_NAME SMB_SML0_ME_SDA
J 0
(-2735 3460);
DISPLAY 0.638298 (-2735 3460);
PAINT WHITE (-2735 3460);
WIRE 16 -1 (-2900 3400)(-1825 3400);
FORCEPROP 0 LAST CDS_PHYS_NET_NAME SMB_FRU_U181_3V3AUX_SDA_R
J 0
(-2585 3440);
PAINT MONO (-2585 3440);
DISPLAY INVISIBLE (-2585 3440);
FORCEPROP 2 LAST SIG_NAME SMB_PMBUS_SML1_ME_SCL
J 0
(-2735 3410);
DISPLAY 0.638298 (-2735 3410);
PAINT WHITE (-2735 3410);
WIRE 16 -1 (-2900 3350)(-1825 3350);
FORCEPROP 0 LAST CDS_PHYS_NET_NAME SMB_FRU_U181_3V3AUX_SDA_R
J 0
(-2585 3390);
PAINT MONO (-2585 3390);
DISPLAY INVISIBLE (-2585 3390);
FORCEPROP 2 LAST SIG_NAME SMB_PMBUS_SML1_ME_SDA
J 0
(-2735 3360);
DISPLAY 0.638298 (-2735 3360);
PAINT WHITE (-2735 3360);
WIRE 16 -1 (-2900 3300)(-1825 3300);
FORCEPROP 0 LAST CDS_PHYS_NET_NAME SMB_FRU_U181_3V3AUX_SDA_R
J 0
(-2585 3340);
PAINT MONO (-2585 3340);
DISPLAY INVISIBLE (-2585 3340);
FORCEPROP 2 LAST SIG_NAME RST_RSMRST_NM_HDR_N
J 0
(-2735 3310);
DISPLAY 0.638298 (-2735 3310);
PAINT WHITE (-2735 3310);
WIRE 16 -1 (-1225 3300)(-1150 3300);
WIRE 16 -1 (-1150 3400)(-1150 3300);
WIRE 16 -1 (-1225 3400)(-1150 3400);
WIRE 16 -1 (-1150 3500)(-1150 3400);
WIRE 16 -1 (-1225 3500)(-1150 3500);
WIRE 16 -1 (-1225 3450)(-150 3450);
FORCEPROP 0 LAST CDS_PHYS_NET_NAME SMB_FRU_U181_3V3AUX_SDA_R
J 0
(-910 3490);
PAINT MONO (-910 3490);
DISPLAY INVISIBLE (-910 3490);
FORCEPROP 2 LAST SIG_NAME IRQ_SML0_ALERT_R1_N
J 0
(-1085 3460);
DISPLAY 0.638298 (-1085 3460);
PAINT WHITE (-1085 3460);
WIRE 16 -1 (-1225 3350)(-150 3350);
FORCEPROP 0 LAST CDS_PHYS_NET_NAME SMB_FRU_U181_3V3AUX_SDA_R
J 0
(-910 3390);
PAINT MONO (-910 3390);
DISPLAY INVISIBLE (-910 3390);
FORCEPROP 2 LAST SIG_NAME IRQ_SML1_PMBUS_ALERT_R_N
J 0
(-1085 3360);
DISPLAY 0.638298 (-1085 3360);
PAINT WHITE (-1085 3360);
WIRE 16 -1 (-2900 3050)(-1825 3050);
FORCEPROP 0 LAST CDS_PHYS_NET_NAME SMB_FRU_U181_3V3AUX_SDA_R
J 0
(-2585 3090);
PAINT MONO (-2585 3090);
DISPLAY INVISIBLE (-2585 3090);
FORCEPROP 2 LAST SIG_NAME FM_BIOS_POST_CMPLT_HDR_N
J 0
(-2735 3060);
DISPLAY 0.638298 (-2735 3060);
PAINT WHITE (-2735 3060);
WIRE 16 -1 (-2900 3250)(-1825 3250);
FORCEPROP 0 LAST CDS_PHYS_NET_NAME SMB_FRU_U181_3V3AUX_SDA_R
J 0
(-2585 3290);
PAINT MONO (-2585 3290);
DISPLAY INVISIBLE (-2585 3290);
FORCEPROP 2 LAST SIG_NAME SMB_HOST_ME_SCL
J 0
(-2735 3260);
DISPLAY 0.638298 (-2735 3260);
PAINT WHITE (-2735 3260);
WIRE 16 -1 (-2500 2325)(-1500 2325);
FORCEPROP 0 LAST CDS_PHYS_NET_NAME SMB_FRU_U181_3V3AUX_SDA
J 0
(-2475 2367);
PAINT MONO (-2475 2367);
DISPLAY INVISIBLE (-2475 2367);
FORCEPROP 0 LAST SIG_NAME IRQ_SML0_ALERT_R_N
J 0
(-2400 2335);
DISPLAY 0.680851 (-2400 2335);
PAINT WHITE (-2400 2335);
WIRE 16 -1 (-200 1925)(-1300 1925);
FORCEPROP 2 LAST SIG_NAME SMB_HOST_ME_SCL
J 0
(-910 1935);
DISPLAY 0.680851 (-910 1935);
PAINT WHITE (-910 1935);
WIRE 16 -1 (-200 1725)(-1300 1725);
FORCEPROP 2 LAST SIG_NAME SMB_HOST_ME_SDA
J 0
(-910 1735);
DISPLAY 0.680851 (-910 1735);
PAINT WHITE (-910 1735);
WIRE 16 -1 (-1500 1725)(-2500 1725);
FORCEPROP 2 LAST SIG_NAME SMB_HOST_3V3AUX_SDA_R5
J 0
(-2385 1735);
DISPLAY 0.680851 (-2385 1735);
PAINT WHITE (-2385 1735);
WIRE 16 -1 (-25 3100)(725 3100);
FORCEPROP 0 LAST CDS_PHYS_NET_NAME SMB_FRU_U181_3V3AUX_SDA_R
J 0
(290 3140);
PAINT MONO (290 3140);
DISPLAY INVISIBLE (290 3140);
FORCEPROP 2 LAST SIG_NAME PWRGD_PS_PWROK
J 0
(290 3110);
DISPLAY 0.638298 (290 3110);
PAINT WHITE (290 3110);
DOT 1 (-1150 3250);
DOT 1 (-1150 3300);
DOT 1 (-1150 3400);
DOT 1 (-1900 3100);
FORCENOTE
20210705 MODIFY FOR GT
(-5600 5650) 0;
DISPLAY LEFT (-5600 5650);
DISPLAY 2.510638 (-5600 5650);
PAINT PINK (-5600 5650);
QUIT
